(kicad_pcb
	(version 20260206)
	(generator "pcbnew")
	(generator_version "10.0")
	(general
		(thickness 1.6)
		(legacy_teardrops no)
	)
	(paper "A4")
	(title_block
		(title "03242023_DA0F0TMBIJ0_F0T_Motherboard_J_brd_V01_OCP.brd")
		(comment 1 "Grand Teton / footprint 3833 of 6105 (J14), pads 113-224 of 291")
	)
	(layers
		(0 "F.Cu" signal "TOP")
		(4 "In1.Cu" signal "GND")
		(6 "In2.Cu" signal "IN1")
		(8 "In3.Cu" signal "GND1")
		(10 "In4.Cu" signal "IN2")
		(12 "In5.Cu" signal "GND2")
		(14 "In6.Cu" signal "IN3")
		(16 "In7.Cu" signal "GND3")
		(18 "In8.Cu" signal "VCC")
		(20 "In9.Cu" signal "VCC1")
		(22 "In10.Cu" signal "GND4")
		(24 "In11.Cu" signal "IN4")
		(26 "In12.Cu" signal "GND5")
		(28 "In13.Cu" signal "IN5")
		(30 "In14.Cu" signal "GND6")
		(32 "In15.Cu" signal "IN6")
		(34 "In16.Cu" signal "GND7")
		(2 "B.Cu" signal "BOTTOM")
		(9 "F.Adhes" user "F.Adhesive")
		(11 "B.Adhes" user "B.Adhesive")
		(13 "F.Paste" user "Package Geometry/Pastemask Top")
		(15 "B.Paste" user "Package Geometry/Pastemask Bottom")
		(5 "F.SilkS" user "Ref Des/Silkscreen Top")
		(7 "B.SilkS" user "Ref Des/Silkscreen Bottom")
		(1 "F.Mask" user "Board Geometry/Soldermask Top")
		(3 "B.Mask" user "Board Geometry/Soldermask Bottom")
		(17 "Dwgs.User" user "User.Drawings")
		(19 "Cmts.User" user "User.Comments")
		(21 "Eco1.User" user "User.Eco1")
		(23 "Eco2.User" user "User.Eco2")
		(25 "Edge.Cuts" user "Board Geometry/Outline")
		(27 "Margin" user)
		(31 "F.CrtYd" user "Package Geometry/Place Bound Top")
		(29 "B.CrtYd" user "Package Geometry/Place Bound Bottom")
		(35 "F.Fab" user "Ref Des/Assembly Top")
		(33 "B.Fab" user "Ref Des/Assembly Bottom")
	)
	(footprint ""
		(layer "F.Cu")
		(at 438.978548 -258.091686)
		(property "Reference" "J14"
			(at -3.683 -81.702148 0)
			(unlocked yes)
			(layer "F.SilkS")
			(effects
				(font
					(size 0.7874 0.5842)
					(thickness 0.1524)
				)
				(justify left)
			)
		)
		(property "Value" ""
			(at 0 0 0)
			(layer "F.Fab")
			(effects
				(font
					(size 1.27 1.27)
				)
			)
		)
		(duplicate_pad_numbers_are_jumpers no)
		(pad "113" smd rect
			(at -2.050034 36.975034 270)
			(size 0.519938 1.4986)
			(layers "F.Cu" "F.Mask" "F.Paste")
			(net "M_G_CPU0_SB_DQ<9>")
		)
		(pad "114" smd rect
			(at -2.050034 37.824918 270)
			(size 0.519938 1.4986)
			(layers "F.Cu" "F.Mask" "F.Paste")
			(net "GND")
		)
		(pad "115" smd rect
			(at -2.050034 38.675056 270)
			(size 0.519938 1.4986)
			(layers "F.Cu" "F.Mask" "F.Paste")
			(net "M_G_CPU0_SB_DQS_DP<1>")
		)
		(pad "116" smd rect
			(at -2.050034 39.52494 270)
			(size 0.519938 1.4986)
			(layers "F.Cu" "F.Mask" "F.Paste")
			(net "M_G_CPU0_SB_DQS_DN<1>")
		)
		(pad "117" smd rect
			(at -2.050034 40.375078 270)
			(size 0.519938 1.4986)
			(layers "F.Cu" "F.Mask" "F.Paste")
			(net "GND")
		)
		(pad "118" smd rect
			(at -2.050034 41.224962 270)
			(size 0.519938 1.4986)
			(layers "F.Cu" "F.Mask" "F.Paste")
			(net "M_G_CPU0_SB_DQ<12>")
		)
		(pad "119" smd rect
			(at -2.050034 42.0751 270)
			(size 0.519938 1.4986)
			(layers "F.Cu" "F.Mask" "F.Paste")
			(net "GND")
		)
		(pad "120" smd rect
			(at -2.050034 42.924984 270)
			(size 0.519938 1.4986)
			(layers "F.Cu" "F.Mask" "F.Paste")
			(net "M_G_CPU0_SB_DQ<13>")
		)
		(pad "121" smd rect
			(at -2.050034 43.775122 270)
			(size 0.519938 1.4986)
			(layers "F.Cu" "F.Mask" "F.Paste")
			(net "GND")
		)
		(pad "122" smd rect
			(at -2.050034 44.625006 270)
			(size 0.519938 1.4986)
			(layers "F.Cu" "F.Mask" "F.Paste")
			(net "M_G_CPU0_SB_DQ<16>")
		)
		(pad "123" smd rect
			(at -2.050034 45.47489 270)
			(size 0.519938 1.4986)
			(layers "F.Cu" "F.Mask" "F.Paste")
			(net "GND")
		)
		(pad "124" smd rect
			(at -2.050034 46.325028 270)
			(size 0.519938 1.4986)
			(layers "F.Cu" "F.Mask" "F.Paste")
			(net "M_G_CPU0_SB_DQ<17>")
		)
		(pad "125" smd rect
			(at -2.050034 47.174912 270)
			(size 0.519938 1.4986)
			(layers "F.Cu" "F.Mask" "F.Paste")
			(net "GND")
		)
		(pad "126" smd rect
			(at -2.050034 48.02505 270)
			(size 0.519938 1.4986)
			(layers "F.Cu" "F.Mask" "F.Paste")
			(net "M_G_CPU0_SB_DQS_DP<2>")
		)
		(pad "127" smd rect
			(at -2.050034 48.874934 270)
			(size 0.519938 1.4986)
			(layers "F.Cu" "F.Mask" "F.Paste")
			(net "M_G_CPU0_SB_DQS_DN<2>")
		)
		(pad "128" smd rect
			(at -2.050034 49.725072 270)
			(size 0.519938 1.4986)
			(layers "F.Cu" "F.Mask" "F.Paste")
			(net "GND")
		)
		(pad "129" smd rect
			(at -2.050034 50.574956 270)
			(size 0.519938 1.4986)
			(layers "F.Cu" "F.Mask" "F.Paste")
			(net "M_G_CPU0_SB_DQ<20>")
		)
		(pad "130" smd rect
			(at -2.050034 51.425094 270)
			(size 0.519938 1.4986)
			(layers "F.Cu" "F.Mask" "F.Paste")
			(net "GND")
		)
		(pad "131" smd rect
			(at -2.050034 52.274978 270)
			(size 0.519938 1.4986)
			(layers "F.Cu" "F.Mask" "F.Paste")
			(net "M_G_CPU0_SB_DQ<21>")
		)
		(pad "132" smd rect
			(at -2.050034 53.125116 270)
			(size 0.519938 1.4986)
			(layers "F.Cu" "F.Mask" "F.Paste")
			(net "GND")
		)
		(pad "133" smd rect
			(at -2.050034 53.975 270)
			(size 0.519938 1.4986)
			(layers "F.Cu" "F.Mask" "F.Paste")
			(net "M_G_CPU0_SB_DQ<24>")
		)
		(pad "134" smd rect
			(at -2.050034 54.824884 270)
			(size 0.519938 1.4986)
			(layers "F.Cu" "F.Mask" "F.Paste")
			(net "GND")
		)
		(pad "135" smd rect
			(at -2.050034 55.675022 270)
			(size 0.519938 1.4986)
			(layers "F.Cu" "F.Mask" "F.Paste")
			(net "M_G_CPU0_SB_DQ<25>")
		)
		(pad "136" smd rect
			(at -2.050034 56.524906 270)
			(size 0.519938 1.4986)
			(layers "F.Cu" "F.Mask" "F.Paste")
			(net "GND")
		)
		(pad "137" smd rect
			(at -2.050034 57.375044 270)
			(size 0.519938 1.4986)
			(layers "F.Cu" "F.Mask" "F.Paste")
			(net "M_G_CPU0_SB_DQS_DP<3>")
		)
		(pad "138" smd rect
			(at -2.050034 58.224928 270)
			(size 0.519938 1.4986)
			(layers "F.Cu" "F.Mask" "F.Paste")
			(net "M_G_CPU0_SB_DQS_DN<3>")
		)
		(pad "139" smd rect
			(at -2.050034 59.075066 270)
			(size 0.519938 1.4986)
			(layers "F.Cu" "F.Mask" "F.Paste")
			(net "GND")
		)
		(pad "140" smd rect
			(at -2.050034 59.92495 270)
			(size 0.519938 1.4986)
			(layers "F.Cu" "F.Mask" "F.Paste")
			(net "M_G_CPU0_SB_DQ<28>")
		)
		(pad "141" smd rect
			(at -2.050034 60.775088 270)
			(size 0.519938 1.4986)
			(layers "F.Cu" "F.Mask" "F.Paste")
			(net "GND")
		)
		(pad "142" smd rect
			(at -2.050034 61.624972 270)
			(size 0.519938 1.4986)
			(layers "F.Cu" "F.Mask" "F.Paste")
			(net "M_G_CPU0_SB_DQ<29>")
		)
		(pad "143" smd rect
			(at -2.050034 62.47511 270)
			(size 0.519938 1.4986)
			(layers "F.Cu" "F.Mask" "F.Paste")
			(net "GND")
		)
		(pad "144" smd rect
			(at -2.050034 63.324994 270)
			(size 0.519938 1.4986)
			(layers "F.Cu" "F.Mask" "F.Paste")
			(net "TP_CHG_CPU0_DIMM2_FRU_1")
		)
		(pad "145" smd rect
			(at 2.050034 -63.324994 270)
			(size 0.519938 1.4986)
			(layers "F.Cu" "F.Mask" "F.Paste")
			(net "P12V_S3_AUX_CPU0_NVDIMM")
		)
		(pad "146" smd rect
			(at 2.050034 -62.47511 270)
			(size 0.519938 1.4986)
			(layers "F.Cu" "F.Mask" "F.Paste")
			(net "P12V_S3_AUX_CPU0_NVDIMM")
		)
		(pad "147" smd rect
			(at 2.050034 -61.624972 270)
			(size 0.519938 1.4986)
			(layers "F.Cu" "F.Mask" "F.Paste")
			(net "PWRGD_CHG_CPU0_DIMM2")
		)
		(pad "148" smd rect
			(at 2.050034 -60.775088 270)
			(size 0.519938 1.4986)
			(layers "F.Cu" "F.Mask" "F.Paste")
			(net "PD_CHG_CPU0_DIMM2_SAA")
		)
		(pad "149" smd rect
			(at 2.050034 -59.92495 270)
			(size 0.519938 1.4986)
			(layers "F.Cu" "F.Mask" "F.Paste")
			(net "TP_CHG_CPU0_DIMM2_FRU_2")
		)
		(pad "150" smd rect
			(at 2.050034 -59.075066 270)
			(size 0.519938 1.4986)
			(layers "F.Cu" "F.Mask" "F.Paste")
			(net "TP_CHG_CPU0_DIMM2_FRU_3")
		)
		(pad "151" smd rect
			(at 2.050034 -58.224928 270)
			(size 0.519938 1.4986)
			(layers "F.Cu" "F.Mask" "F.Paste")
			(net "GND")
		)
		(pad "152" smd rect
			(at 2.050034 -57.375044 270)
			(size 0.519938 1.4986)
			(layers "F.Cu" "F.Mask" "F.Paste")
			(net "M_G_CPU0_SA_DQ<2>")
		)
		(pad "153" smd rect
			(at 2.050034 -56.524906 270)
			(size 0.519938 1.4986)
			(layers "F.Cu" "F.Mask" "F.Paste")
			(net "GND")
		)
		(pad "154" smd rect
			(at 2.050034 -55.675022 270)
			(size 0.519938 1.4986)
			(layers "F.Cu" "F.Mask" "F.Paste")
			(net "M_G_CPU0_SA_DQ<3>")
		)
		(pad "155" smd rect
			(at 2.050034 -54.824884 270)
			(size 0.519938 1.4986)
			(layers "F.Cu" "F.Mask" "F.Paste")
			(net "GND")
		)
		(pad "156" smd rect
			(at 2.050034 -53.975 270)
			(size 0.519938 1.4986)
			(layers "F.Cu" "F.Mask" "F.Paste")
			(net "M_G_CPU0_SA_DQS_DN<5>")
		)
		(pad "157" smd rect
			(at 2.050034 -53.125116 270)
			(size 0.519938 1.4986)
			(layers "F.Cu" "F.Mask" "F.Paste")
			(net "M_G_CPU0_SA_DQS_DP<5>")
		)
		(pad "158" smd rect
			(at 2.050034 -52.274978 270)
			(size 0.519938 1.4986)
			(layers "F.Cu" "F.Mask" "F.Paste")
			(net "GND")
		)
		(pad "159" smd rect
			(at 2.050034 -51.425094 270)
			(size 0.519938 1.4986)
			(layers "F.Cu" "F.Mask" "F.Paste")
			(net "M_G_CPU0_SA_DQ<6>")
		)
		(pad "160" smd rect
			(at 2.050034 -50.574956 270)
			(size 0.519938 1.4986)
			(layers "F.Cu" "F.Mask" "F.Paste")
			(net "GND")
		)
		(pad "161" smd rect
			(at 2.050034 -49.725072 270)
			(size 0.519938 1.4986)
			(layers "F.Cu" "F.Mask" "F.Paste")
			(net "M_G_CPU0_SA_DQ<7>")
		)
		(pad "162" smd rect
			(at 2.050034 -48.874934 270)
			(size 0.519938 1.4986)
			(layers "F.Cu" "F.Mask" "F.Paste")
			(net "GND")
		)
		(pad "163" smd rect
			(at 2.050034 -48.02505 270)
			(size 0.519938 1.4986)
			(layers "F.Cu" "F.Mask" "F.Paste")
			(net "M_G_CPU0_SA_DQ<10>")
		)
		(pad "164" smd rect
			(at 2.050034 -47.174912 270)
			(size 0.519938 1.4986)
			(layers "F.Cu" "F.Mask" "F.Paste")
			(net "GND")
		)
		(pad "165" smd rect
			(at 2.050034 -46.325028 270)
			(size 0.519938 1.4986)
			(layers "F.Cu" "F.Mask" "F.Paste")
			(net "M_G_CPU0_SA_DQ<11>")
		)
		(pad "166" smd rect
			(at 2.050034 -45.47489 270)
			(size 0.519938 1.4986)
			(layers "F.Cu" "F.Mask" "F.Paste")
			(net "GND")
		)
		(pad "167" smd rect
			(at 2.050034 -44.625006 270)
			(size 0.519938 1.4986)
			(layers "F.Cu" "F.Mask" "F.Paste")
			(net "M_G_CPU0_SA_DQS_DN<6>")
		)
		(pad "168" smd rect
			(at 2.050034 -43.775122 270)
			(size 0.519938 1.4986)
			(layers "F.Cu" "F.Mask" "F.Paste")
			(net "M_G_CPU0_SA_DQS_DP<6>")
		)
		(pad "169" smd rect
			(at 2.050034 -42.924984 270)
			(size 0.519938 1.4986)
			(layers "F.Cu" "F.Mask" "F.Paste")
			(net "GND")
		)
		(pad "170" smd rect
			(at 2.050034 -42.0751 270)
			(size 0.519938 1.4986)
			(layers "F.Cu" "F.Mask" "F.Paste")
			(net "M_G_CPU0_SA_DQ<14>")
		)
		(pad "171" smd rect
			(at 2.050034 -41.224962 270)
			(size 0.519938 1.4986)
			(layers "F.Cu" "F.Mask" "F.Paste")
			(net "GND")
		)
		(pad "172" smd rect
			(at 2.050034 -40.375078 270)
			(size 0.519938 1.4986)
			(layers "F.Cu" "F.Mask" "F.Paste")
			(net "M_G_CPU0_SA_DQ<15>")
		)
		(pad "173" smd rect
			(at 2.050034 -39.52494 270)
			(size 0.519938 1.4986)
			(layers "F.Cu" "F.Mask" "F.Paste")
			(net "GND")
		)
		(pad "174" smd rect
			(at 2.050034 -38.675056 270)
			(size 0.519938 1.4986)
			(layers "F.Cu" "F.Mask" "F.Paste")
			(net "M_G_CPU0_SA_DQ<18>")
		)
		(pad "175" smd rect
			(at 2.050034 -37.824918 270)
			(size 0.519938 1.4986)
			(layers "F.Cu" "F.Mask" "F.Paste")
			(net "GND")
		)
		(pad "176" smd rect
			(at 2.050034 -36.975034 270)
			(size 0.519938 1.4986)
			(layers "F.Cu" "F.Mask" "F.Paste")
			(net "M_G_CPU0_SA_DQ<19>")
		)
		(pad "177" smd rect
			(at 2.050034 -36.124896 270)
			(size 0.519938 1.4986)
			(layers "F.Cu" "F.Mask" "F.Paste")
			(net "GND")
		)
		(pad "178" smd rect
			(at 2.050034 -35.275012 270)
			(size 0.519938 1.4986)
			(layers "F.Cu" "F.Mask" "F.Paste")
			(net "M_G_CPU0_SA_DQS_DN<7>")
		)
		(pad "179" smd rect
			(at 2.050034 -34.425128 270)
			(size 0.519938 1.4986)
			(layers "F.Cu" "F.Mask" "F.Paste")
			(net "M_G_CPU0_SA_DQS_DP<7>")
		)
		(pad "180" smd rect
			(at 2.050034 -33.57499 270)
			(size 0.519938 1.4986)
			(layers "F.Cu" "F.Mask" "F.Paste")
			(net "GND")
		)
		(pad "181" smd rect
			(at 2.050034 -32.725106 270)
			(size 0.519938 1.4986)
			(layers "F.Cu" "F.Mask" "F.Paste")
			(net "M_G_CPU0_SA_DQ<22>")
		)
		(pad "182" smd rect
			(at 2.050034 -31.874968 270)
			(size 0.519938 1.4986)
			(layers "F.Cu" "F.Mask" "F.Paste")
			(net "GND")
		)
		(pad "183" smd rect
			(at 2.050034 -31.025084 270)
			(size 0.519938 1.4986)
			(layers "F.Cu" "F.Mask" "F.Paste")
			(net "M_G_CPU0_SA_DQ<23>")
		)
		(pad "184" smd rect
			(at 2.050034 -30.174946 270)
			(size 0.519938 1.4986)
			(layers "F.Cu" "F.Mask" "F.Paste")
			(net "GND")
		)
		(pad "185" smd rect
			(at 2.050034 -29.325062 270)
			(size 0.519938 1.4986)
			(layers "F.Cu" "F.Mask" "F.Paste")
			(net "M_G_CPU0_SA_DQ<26>")
		)
		(pad "186" smd rect
			(at 2.050034 -28.474924 270)
			(size 0.519938 1.4986)
			(layers "F.Cu" "F.Mask" "F.Paste")
			(net "GND")
		)
		(pad "187" smd rect
			(at 2.050034 -27.62504 270)
			(size 0.519938 1.4986)
			(layers "F.Cu" "F.Mask" "F.Paste")
			(net "M_G_CPU0_SA_DQ<27>")
		)
		(pad "188" smd rect
			(at 2.050034 -26.774902 270)
			(size 0.519938 1.4986)
			(layers "F.Cu" "F.Mask" "F.Paste")
			(net "GND")
		)
		(pad "189" smd rect
			(at 2.050034 -25.925018 270)
			(size 0.519938 1.4986)
			(layers "F.Cu" "F.Mask" "F.Paste")
			(net "M_G_CPU0_SA_DQS_DN<8>")
		)
		(pad "190" smd rect
			(at 2.050034 -25.07488 270)
			(size 0.519938 1.4986)
			(layers "F.Cu" "F.Mask" "F.Paste")
			(net "M_G_CPU0_SA_DQS_DP<8>")
		)
		(pad "191" smd rect
			(at 2.050034 -24.224996 270)
			(size 0.519938 1.4986)
			(layers "F.Cu" "F.Mask" "F.Paste")
			(net "GND")
		)
		(pad "192" smd rect
			(at 2.050034 -23.375112 270)
			(size 0.519938 1.4986)
			(layers "F.Cu" "F.Mask" "F.Paste")
			(net "M_G_CPU0_SA_DQ<30>")
		)
		(pad "193" smd rect
			(at 2.050034 -22.524974 270)
			(size 0.519938 1.4986)
			(layers "F.Cu" "F.Mask" "F.Paste")
			(net "GND")
		)
		(pad "194" smd rect
			(at 2.050034 -21.67509 270)
			(size 0.519938 1.4986)
			(layers "F.Cu" "F.Mask" "F.Paste")
			(net "M_G_CPU0_SA_DQ<31>")
		)
		(pad "195" smd rect
			(at 2.050034 -20.824952 270)
			(size 0.519938 1.4986)
			(layers "F.Cu" "F.Mask" "F.Paste")
			(net "GND")
		)
		(pad "196" smd rect
			(at 2.050034 -19.975068 270)
			(size 0.519938 1.4986)
			(layers "F.Cu" "F.Mask" "F.Paste")
			(net "M_G_CPU0_SA_CB<2>")
		)
		(pad "197" smd rect
			(at 2.050034 -19.12493 270)
			(size 0.519938 1.4986)
			(layers "F.Cu" "F.Mask" "F.Paste")
			(net "GND")
		)
		(pad "198" smd rect
			(at 2.050034 -18.275046 270)
			(size 0.519938 1.4986)
			(layers "F.Cu" "F.Mask" "F.Paste")
			(net "M_G_CPU0_SA_CB<3>")
		)
		(pad "199" smd rect
			(at 2.050034 -17.424908 270)
			(size 0.519938 1.4986)
			(layers "F.Cu" "F.Mask" "F.Paste")
			(net "GND")
		)
		(pad "200" smd rect
			(at 2.050034 -16.575024 270)
			(size 0.519938 1.4986)
			(layers "F.Cu" "F.Mask" "F.Paste")
			(net "M_G_CPU0_SA_DQS_DN<9>")
		)
		(pad "201" smd rect
			(at 2.050034 -15.724886 270)
			(size 0.519938 1.4986)
			(layers "F.Cu" "F.Mask" "F.Paste")
			(net "M_G_CPU0_SA_DQS_DP<9>")
		)
		(pad "202" smd rect
			(at 2.050034 -14.875002 270)
			(size 0.519938 1.4986)
			(layers "F.Cu" "F.Mask" "F.Paste")
			(net "GND")
		)
		(pad "203" smd rect
			(at 2.050034 -14.025118 270)
			(size 0.519938 1.4986)
			(layers "F.Cu" "F.Mask" "F.Paste")
			(net "M_G_CPU0_SA_CB<6>")
		)
		(pad "204" smd rect
			(at 2.050034 -13.17498 270)
			(size 0.519938 1.4986)
			(layers "F.Cu" "F.Mask" "F.Paste")
			(net "GND")
		)
		(pad "205" smd rect
			(at 2.050034 -12.325096 270)
			(size 0.519938 1.4986)
			(layers "F.Cu" "F.Mask" "F.Paste")
			(net "M_G_CPU0_SA_CB<7>")
		)
		(pad "206" smd rect
			(at 2.050034 -11.474958 270)
			(size 0.519938 1.4986)
			(layers "F.Cu" "F.Mask" "F.Paste")
			(net "GND")
		)
		(pad "207" smd rect
			(at 2.050034 -10.625074 270)
			(size 0.519938 1.4986)
			(layers "F.Cu" "F.Mask" "F.Paste")
			(net "RST_M_GH_CPU0_FPGA_N")
		)
		(pad "208" smd rect
			(at 2.050034 -9.774936 270)
			(size 0.519938 1.4986)
			(layers "F.Cu" "F.Mask" "F.Paste")
			(net "GND")
		)
		(pad "209" smd rect
			(at 2.050034 -8.925052 270)
			(size 0.519938 1.4986)
			(layers "F.Cu" "F.Mask" "F.Paste")
			(net "M_G_CPU0_SA_CS_N<3>")
		)
		(pad "210" smd rect
			(at 2.050034 -8.074914 270)
			(size 0.519938 1.4986)
			(layers "F.Cu" "F.Mask" "F.Paste")
			(net "GND")
		)
		(pad "211" smd rect
			(at 2.050034 -7.22503 270)
			(size 0.519938 1.4986)
			(layers "F.Cu" "F.Mask" "F.Paste")
			(net "M_G_CPU0_SA_CA<1>")
		)
		(pad "212" smd rect
			(at 2.050034 -6.374892 270)
			(size 0.519938 1.4986)
			(layers "F.Cu" "F.Mask" "F.Paste")
			(net "GND")
		)
		(pad "213" smd rect
			(at 2.050034 -5.525008 270)
			(size 0.519938 1.4986)
			(layers "F.Cu" "F.Mask" "F.Paste")
			(net "M_G_CPU0_SA_CA<3>")
		)
		(pad "214" smd rect
			(at 2.050034 -4.675124 270)
			(size 0.519938 1.4986)
			(layers "F.Cu" "F.Mask" "F.Paste")
			(net "GND")
		)
		(pad "215" smd rect
			(at 2.050034 -3.824986 270)
			(size 0.519938 1.4986)
			(layers "F.Cu" "F.Mask" "F.Paste")
			(net "M_G_CPU0_SA_CA<5>")
		)
		(pad "216" smd rect
			(at 2.050034 -2.975102 270)
			(size 0.519938 1.4986)
			(layers "F.Cu" "F.Mask" "F.Paste")
			(net "GND")
		)
		(pad "217" smd rect
			(at 2.050034 -2.124964 270)
			(size 0.519938 1.4986)
			(layers "F.Cu" "F.Mask" "F.Paste")
			(net "M_G_CPU0_CLK_DP<1>")
		)
		(pad "218" smd rect
			(at 2.050034 -1.27508 270)
			(size 0.519938 1.4986)
			(layers "F.Cu" "F.Mask" "F.Paste")
			(net "M_G_CPU0_CLK_DN<1>")
		)
		(pad "219" smd rect
			(at 2.050034 -0.424942 270)
			(size 0.519938 1.4986)
			(layers "F.Cu" "F.Mask" "F.Paste")
			(net "GND")
		)
		(pad "220" smd rect
			(at 2.050034 5.525008 270)
			(size 0.519938 1.4986)
			(layers "F.Cu" "F.Mask" "F.Paste")
			(net "TP_CHG_CPU0_DIMM2_FRU_4")
		)
		(pad "221" smd rect
			(at 2.050034 6.374892 270)
			(size 0.519938 1.4986)
			(layers "F.Cu" "F.Mask" "F.Paste")
			(net "M_G_CPU0_SB_CA<1>")
		)
		(pad "222" smd rect
			(at 2.050034 7.22503 270)
			(size 0.519938 1.4986)
			(layers "F.Cu" "F.Mask" "F.Paste")
			(net "GND")
		)
		(pad "223" smd rect
			(at 2.050034 8.074914 270)
			(size 0.519938 1.4986)
			(layers "F.Cu" "F.Mask" "F.Paste")
			(net "M_G_CPU0_SB_CA<3>")
		)
		(pad "224" smd rect
			(at 2.050034 8.925052 270)
			(size 0.519938 1.4986)
			(layers "F.Cu" "F.Mask" "F.Paste")
			(net "GND")
		)
	)
)
